# discovery-power-board-v1-revB — discovery-cache.lib (kicad-symbol-library)
EESchema-LIBRARY Version 2.4
#encoding utf-8
#
# Connector_Generic_Conn_02x03_Counter_Clockwise
#
DEF Connector_Generic_Conn_02x03_Counter_Clockwise J 0 40 Y N 1 F N
F0 "J" 50 200 50 H V C CNN
F1 "Connector_Generic_Conn_02x03_Counter_Clockwise" 50 -200 50 H V C CNN
F2 "" 0 0 50 H I C CNN
F3 "" 0 0 50 H I C CNN
$FPLIST
 Connector*:*_2x??_*
$ENDFPLIST
DRAW
S -50 -95 0 -105 1 1 6 N
S -50 5 0 -5 1 1 6 N
S -50 105 0 95 1 1 6 N
S -50 150 150 -150 1 1 10 f
S 150 -95 100 -105 1 1 6 N
S 150 5 100 -5 1 1 6 N
S 150 105 100 95 1 1 6 N
X Pin_1 1 -200 100 150 R 50 50 1 1 P
X Pin_2 2 -200 0 150 R 50 50 1 1 P
X Pin_3 3 -200 -100 150 R 50 50 1 1 P
X Pin_4 4 300 -100 150 L 50 50 1 1 P
X Pin_5 5 300 0 150 L 50 50 1 1 P
X Pin_6 6 300 100 150 L 50 50 1 1 P
ENDDRAW
ENDDEF
#
# Connector_Generic_Conn_02x04_Counter_Clockwise
#
DEF Connector_Generic_Conn_02x04_Counter_Clockwise J 0 40 Y N 1 F N
F0 "J" 50 200 50 H V C CNN
F1 "Connector_Generic_Conn_02x04_Counter_Clockwise" 50 -300 50 H V C CNN
F2 "" 0 0 50 H I C CNN
F3 "" 0 0 50 H I C CNN
$FPLIST
 Connector*:*_2x??_*
$ENDFPLIST
DRAW
S -50 -195 0 -205 1 1 6 N
S -50 -95 0 -105 1 1 6 N
S -50 5 0 -5 1 1 6 N
S -50 105 0 95 1 1 6 N
S -50 150 150 -250 1 1 10 f
S 150 -195 100 -205 1 1 6 N
S 150 -95 100 -105 1 1 6 N
S 150 5 100 -5 1 1 6 N
S 150 105 100 95 1 1 6 N
X Pin_1 1 -200 100 150 R 50 50 1 1 P
X Pin_2 2 -200 0 150 R 50 50 1 1 P
X Pin_3 3 -200 -100 150 R 50 50 1 1 P
X Pin_4 4 -200 -200 150 R 50 50 1 1 P
X Pin_5 5 300 -200 150 L 50 50 1 1 P
X Pin_6 6 300 -100 150 L 50 50 1 1 P
X Pin_7 7 300 0 150 L 50 50 1 1 P
X Pin_8 8 300 100 150 L 50 50 1 1 P
ENDDRAW
ENDDEF
#
# Connector_TestPoint
#
DEF Connector_TestPoint TP 0 30 N N 1 F N
F0 "TP" 0 270 50 H V C CNN
F1 "Connector_TestPoint" 0 200 50 H V C CNN
F2 "" 200 0 50 H I C CNN
F3 "" 200 0 50 H I C CNN
$FPLIST
 Pin*
 Test*
$ENDFPLIST
DRAW
C 0 130 30 0 1 0 N
X 1 1 0 0 100 U 50 50 1 1 P
ENDDRAW
ENDDEF
#
# power_+12V
#
DEF power_+12V #PWR 0 0 Y Y 1 F P
F0 "#PWR" 0 -150 50 H I C CNN
F1 "power_+12V" 0 140 50 H V C CNN
F2 "" 0 0 50 H I C CNN
F3 "" 0 0 50 H I C CNN
DRAW
P 2 0 1 0 -30 50 0 100 N
P 2 0 1 0 0 0 0 100 N
P 2 0 1 0 0 100 30 50 N
X +12V 1 0 0 0 U 50 50 1 1 W N
ENDDRAW
ENDDEF
#
# power_GND
#
DEF power_GND #PWR 0 0 Y Y 1 F P
F0 "#PWR" 0 -250 50 H I C CNN
F1 "power_GND" 0 -150 50 H V C CNN
F2 "" 0 0 50 H I C CNN
F3 "" 0 0 50 H I C CNN
DRAW
P 6 0 1 0 0 0 0 -50 50 -50 0 -100 -50 -50 0 -50 N
X GND 1 0 0 0 D 50 50 1 1 W N
ENDDRAW
ENDDEF
#
# power_PWR_FLAG
#
DEF power_PWR_FLAG #FLG 0 0 N N 1 F P
F0 "#FLG" 0 75 50 H I C CNN
F1 "power_PWR_FLAG" 0 150 50 H V C CNN
F2 "" 0 0 50 H I C CNN
F3 "" 0 0 50 H I C CNN
DRAW
P 6 0 1 0 0 0 0 50 -40 75 0 100 40 75 0 50 N
X pwr 1 0 0 0 U 50 50 0 0 w
ENDDRAW
ENDDEF
#
#End Library
